(kicad_pcb
	(version 20260206)
	(generator "pcbnew")
	(generator_version "10.0")
	(general
		(thickness 1.6)
		(legacy_teardrops no)
	)
	(paper "A4")
	(title_block
		(title "9054_F0T_PDB_BD_GPU_F_V04_1213_1550_OCP.brd")
		(comment 1 "Grand Teton / footprints 369-374 of 608")
	)
	(layers
		(0 "F.Cu" signal "TOP")
		(4 "In1.Cu" signal "GND")
		(6 "In2.Cu" signal "IN1")
		(8 "In3.Cu" signal "GND1")
		(10 "In4.Cu" signal "VCC")
		(12 "In5.Cu" signal "VCC1")
		(14 "In6.Cu" signal "GND2")
		(16 "In7.Cu" signal "IN2")
		(18 "In8.Cu" signal "GND3")
		(2 "B.Cu" signal "BOTTOM")
		(9 "F.Adhes" user "F.Adhesive")
		(11 "B.Adhes" user "B.Adhesive")
		(13 "F.Paste" user "Package Geometry/Pastemask Top")
		(15 "B.Paste" user "Package Geometry/Pastemask Bottom")
		(5 "F.SilkS" user "Ref Des/Silkscreen Top")
		(7 "B.SilkS" user "Ref Des/Silkscreen Bottom")
		(1 "F.Mask" user "Board Geometry/Soldermask Top")
		(3 "B.Mask" user "Board Geometry/Soldermask Bottom")
		(17 "Dwgs.User" user "User.Drawings")
		(19 "Cmts.User" user "User.Comments")
		(21 "Eco1.User" user "User.Eco1")
		(23 "Eco2.User" user "User.Eco2")
		(25 "Edge.Cuts" user "Board Geometry/Outline")
		(27 "Margin" user)
		(31 "F.CrtYd" user "Package Geometry/Place Bound Top")
		(29 "B.CrtYd" user "Package Geometry/Place Bound Bottom")
		(35 "F.Fab" user "Ref Des/Assembly Top")
		(33 "B.Fab" user "Ref Des/Assembly Bottom")
	)
	(footprint ""
		(layer "F.Cu")
		(at 124.483876 -29.5402)
		(property "Reference" "PQ42"
			(at 8.913114 -3.609848 0)
			(unlocked yes)
			(layer "F.SilkS")
			(effects
				(font
					(size 0.7874 0.5842)
					(thickness 0.1524)
				)
				(justify left)
			)
		)
		(property "Value" ""
			(at 0 0 0)
			(layer "F.Fab")
			(effects
				(font
					(size 1.27 1.27)
				)
			)
		)
		(duplicate_pad_numbers_are_jumpers no)
		(fp_line
			(start -7.649972 -4.99999)
			(end -7.649972 -3.3274)
			(stroke
				(width 0.1524)
				(type default)
			)
			(layer "F.SilkS")
		)
		(fp_line
			(start -7.649972 -1.7526)
			(end -7.649972 1.7526)
			(stroke
				(width 0.1524)
				(type default)
			)
			(layer "F.SilkS")
		)
		(fp_line
			(start -7.649972 3.3274)
			(end -7.649972 4.99999)
			(stroke
				(width 0.1524)
				(type default)
			)
			(layer "F.SilkS")
		)
		(fp_line
			(start -7.649972 4.99999)
			(end 5.115814 4.99999)
			(stroke
				(width 0.1524)
				(type default)
			)
			(layer "F.SilkS")
		)
		(fp_line
			(start 5.115814 -4.99999)
			(end -7.649972 -4.99999)
			(stroke
				(width 0.1524)
				(type default)
			)
			(layer "F.SilkS")
		)
		(fp_line
			(start 7.630414 4.99999)
			(end 7.649972 4.99999)
			(stroke
				(width 0.1524)
				(type default)
			)
			(layer "F.SilkS")
		)
		(fp_line
			(start 7.649972 -4.99999)
			(end 7.630414 -4.99999)
			(stroke
				(width 0.1524)
				(type default)
			)
			(layer "F.SilkS")
		)
		(fp_line
			(start 7.649972 4.99999)
			(end 7.649972 -4.99999)
			(stroke
				(width 0.1524)
				(type default)
			)
			(layer "F.SilkS")
		)
		(fp_line
			(start -7.649972 -4.99999)
			(end -7.649972 4.99999)
			(stroke
				(width 0.1)
				(type default)
			)
			(layer "F.Fab")
		)
		(fp_line
			(start -7.649972 4.99999)
			(end 7.649972 4.99999)
			(stroke
				(width 0.1)
				(type default)
			)
			(layer "F.Fab")
		)
		(fp_line
			(start 7.649972 -4.99999)
			(end -7.649972 -4.99999)
			(stroke
				(width 0.1)
				(type default)
			)
			(layer "F.Fab")
		)
		(fp_line
			(start 7.649972 4.99999)
			(end 7.649972 -4.99999)
			(stroke
				(width 0.1)
				(type default)
			)
			(layer "F.Fab")
		)
		(pad "D" smd circle
			(at 2.15011 0)
			(size 0 0)
			(layers "F.Cu" "F.Mask" "F.Paste")
			(net "P52V_HS2_DRAIN_2")
		)
		(pad "G" smd rect
			(at -7.050024 -2.54 270)
			(size 1.3208 3.0988)
			(layers "F.Cu" "F.Mask" "F.Paste")
			(net "P52V_HS2_GATE5")
		)
		(pad "S" smd rect
			(at -7.050024 2.54 270)
			(size 1.3208 3.0988)
			(layers "F.Cu" "F.Mask" "F.Paste")
			(net "P52V_HS2")
		)
		(zone
			(layer "F.Cu")
			(hatch none 0.5)
			(connect_pads
				(clearance 0)
			)
			(min_thickness 0.25)
			(keepout
				(tracks not_allowed)
				(vias allowed)
				(pads allowed)
				(copperpour not_allowed)
				(footprints allowed)
			)
			(placement
				(enabled no)
				(sheetname "")
			)
			(fill
				(thermal_gap 0.5)
				(thermal_bridge_width 0.5)
				(island_removal_mode 0)
			)
			(polygon
				(pts
					(xy 129.665476 -34.5186) (xy 116.838476 -34.5186) (xy 116.838476 -32.7914) (xy 119.048276 -32.7914)
					(xy 119.048276 -31.369) (xy 116.838476 -31.369) (xy 116.838476 -27.7114) (xy 119.048276 -27.7114)
					(xy 119.048276 -26.289) (xy 116.838476 -26.289) (xy 116.838476 -24.5618) (xy 129.665476 -24.5618)
					(xy 129.665476 -25.7302) (xy 123.467876 -25.7302) (xy 123.467876 -33.3502) (xy 129.665476 -33.3502)
				)
			)
		)
	)
	(footprint ""
		(layer "F.Cu")
		(at 390.017 -28.575)
		(property "Reference" "PQ17"
			(at -4.03733 3.048 90)
			(unlocked yes)
			(layer "F.SilkS")
			(effects
				(font
					(size 0.7874 0.5842)
					(thickness 0.1524)
				)
				(justify left)
			)
		)
		(property "Value" ""
			(at 0 0 0)
			(layer "F.Fab")
			(effects
				(font
					(size 1.27 1.27)
				)
			)
		)
		(duplicate_pad_numbers_are_jumpers no)
		(fp_line
			(start -1.905 -1.651)
			(end 1.905 -1.651)
			(stroke
				(width 0.1524)
				(type default)
			)
			(layer "F.SilkS")
		)
		(fp_line
			(start -1.905 1.651)
			(end -1.905 -1.651)
			(stroke
				(width 0.1524)
				(type default)
			)
			(layer "F.SilkS")
		)
		(fp_line
			(start 1.905 -1.651)
			(end 1.905 1.651)
			(stroke
				(width 0.1524)
				(type default)
			)
			(layer "F.SilkS")
		)
		(fp_line
			(start 1.905 1.651)
			(end -1.905 1.651)
			(stroke
				(width 0.1524)
				(type default)
			)
			(layer "F.SilkS")
		)
		(fp_line
			(start -1.249934 -1.169924)
			(end -0.649986 -1.169924)
			(stroke
				(width 0.1)
				(type default)
			)
			(layer "F.Fab")
		)
		(fp_line
			(start -1.249934 -0.729996)
			(end -1.249934 -1.169924)
			(stroke
				(width 0.1)
				(type default)
			)
			(layer "F.Fab")
		)
		(fp_line
			(start -1.249934 0.729996)
			(end -0.6985 0.729996)
			(stroke
				(width 0.1)
				(type default)
			)
			(layer "F.Fab")
		)
		(fp_line
			(start -1.249934 1.169924)
			(end -1.249934 0.729996)
			(stroke
				(width 0.1)
				(type default)
			)
			(layer "F.Fab")
		)
		(fp_line
			(start -0.6985 -0.729996)
			(end -1.249934 -0.729996)
			(stroke
				(width 0.1)
				(type default)
			)
			(layer "F.Fab")
		)
		(fp_line
			(start -0.6985 0.729996)
			(end -0.6985 -0.729996)
			(stroke
				(width 0.1)
				(type default)
			)
			(layer "F.Fab")
		)
		(fp_line
			(start -0.649986 -1.524)
			(end 0.6985 -1.524)
			(stroke
				(width 0.1)
				(type default)
			)
			(layer "F.Fab")
		)
		(fp_line
			(start -0.649986 -1.169924)
			(end -0.649986 -1.524)
			(stroke
				(width 0.1)
				(type default)
			)
			(layer "F.Fab")
		)
		(fp_line
			(start -0.649986 1.169924)
			(end -1.249934 1.169924)
			(stroke
				(width 0.1)
				(type default)
			)
			(layer "F.Fab")
		)
		(fp_line
			(start -0.649986 1.524)
			(end -0.649986 1.169924)
			(stroke
				(width 0.1)
				(type default)
			)
			(layer "F.Fab")
		)
		(fp_line
			(start 0.6985 -1.524)
			(end 0.6985 -0.219964)
			(stroke
				(width 0.1)
				(type default)
			)
			(layer "F.Fab")
		)
		(fp_line
			(start 0.6985 -0.219964)
			(end 1.249934 -0.219964)
			(stroke
				(width 0.1)
				(type default)
			)
			(layer "F.Fab")
		)
		(fp_line
			(start 0.6985 0.219964)
			(end 0.6985 1.524)
			(stroke
				(width 0.1)
				(type default)
			)
			(layer "F.Fab")
		)
		(fp_line
			(start 0.6985 1.524)
			(end -0.649986 1.524)
			(stroke
				(width 0.1)
				(type default)
			)
			(layer "F.Fab")
		)
		(fp_line
			(start 1.249934 -0.219964)
			(end 1.249934 0.219964)
			(stroke
				(width 0.1)
				(type default)
			)
			(layer "F.Fab")
		)
		(fp_line
			(start 1.249934 0.219964)
			(end 0.6985 0.219964)
			(stroke
				(width 0.1)
				(type default)
			)
			(layer "F.Fab")
		)
		(pad "B" smd rect
			(at -1.1176 -1.016 270)
			(size 1.016 1.27)
			(layers "F.Cu" "F.Mask" "F.Paste")
			(net "P52V_HS1_EN_DISCHARGE_VBE")
		)
		(pad "C" smd rect
			(at 1.1176 0 270)
			(size 1.016 1.27)
			(layers "F.Cu" "F.Mask" "F.Paste")
			(net "P52V_HS1_EN_DISCHARGE_N")
		)
		(pad "E" smd rect
			(at -1.1176 1.016 270)
			(size 1.016 1.27)
			(layers "F.Cu" "F.Mask" "F.Paste")
			(net "GND")
		)
	)
	(footprint ""
		(layer "F.Cu")
		(at 164.973 -65.786 90)
		(property "Reference" "PC615"
			(at 0 0 90)
			(layer "F.SilkS")
			(hide yes)
			(effects
				(font
					(size 1.27 1.27)
				)
			)
		)
		(property "Value" ""
			(at 0 0 90)
			(layer "F.Fab")
			(effects
				(font
					(size 1.27 1.27)
				)
			)
		)
		(duplicate_pad_numbers_are_jumpers no)
		(fp_line
			(start 0.7874 -0.4064)
			(end 0.7874 0.4064)
			(stroke
				(width 0.1524)
				(type default)
			)
			(layer "F.SilkS")
		)
		(fp_line
			(start -0.7874 -0.4064)
			(end 0.7874 -0.4064)
			(stroke
				(width 0.1524)
				(type default)
			)
			(layer "F.SilkS")
		)
		(fp_line
			(start 0.7874 0.4064)
			(end -0.7874 0.4064)
			(stroke
				(width 0.1524)
				(type default)
			)
			(layer "F.SilkS")
		)
		(fp_line
			(start -0.7874 0.4064)
			(end -0.7874 -0.4064)
			(stroke
				(width 0.1524)
				(type default)
			)
			(layer "F.SilkS")
		)
		(fp_line
			(start -0.12065 -0.305054)
			(end -0.12065 -0.2794)
			(stroke
				(width 0.1)
				(type default)
			)
			(layer "F.Fab")
		)
		(fp_line
			(start -0.67945 -0.305054)
			(end -0.12065 -0.305054)
			(stroke
				(width 0.1)
				(type default)
			)
			(layer "F.Fab")
		)
		(fp_line
			(start 0.67945 -0.3048)
			(end 0.67945 0.3048)
			(stroke
				(width 0.1)
				(type default)
			)
			(layer "F.Fab")
		)
		(fp_line
			(start 0.12065 -0.3048)
			(end 0.67945 -0.3048)
			(stroke
				(width 0.1)
				(type default)
			)
			(layer "F.Fab")
		)
		(fp_line
			(start 0.12065 -0.2794)
			(end 0.12065 -0.3048)
			(stroke
				(width 0.1)
				(type default)
			)
			(layer "F.Fab")
		)
		(fp_line
			(start -0.12065 -0.2794)
			(end 0.12065 -0.2794)
			(stroke
				(width 0.1)
				(type default)
			)
			(layer "F.Fab")
		)
		(fp_line
			(start 0.120396 0.2794)
			(end -0.12065 0.2794)
			(stroke
				(width 0.1)
				(type default)
			)
			(layer "F.Fab")
		)
		(fp_line
			(start -0.12065 0.2794)
			(end -0.12065 0.3048)
			(stroke
				(width 0.1)
				(type default)
			)
			(layer "F.Fab")
		)
		(fp_line
			(start 0.67945 0.3048)
			(end 0.120396 0.3048)
			(stroke
				(width 0.1)
				(type default)
			)
			(layer "F.Fab")
		)
		(fp_line
			(start 0.120396 0.3048)
			(end 0.120396 0.2794)
			(stroke
				(width 0.1)
				(type default)
			)
			(layer "F.Fab")
		)
		(fp_line
			(start -0.12065 0.3048)
			(end -0.67945 0.3048)
			(stroke
				(width 0.1)
				(type default)
			)
			(layer "F.Fab")
		)
		(fp_line
			(start -0.67945 0.3048)
			(end -0.67945 -0.305054)
			(stroke
				(width 0.1)
				(type default)
			)
			(layer "F.Fab")
		)
		(pad "1" smd circle
			(at -0.40005 0 90)
			(size 0 0)
			(layers "F.Cu" "F.Mask" "F.Paste")
			(net "P52V_HS2_EFAULT")
		)
		(pad "2" smd circle
			(at 0.40005 0 90)
			(size 0 0)
			(layers "F.Cu" "F.Mask" "F.Paste")
			(net "GND1_FIELD_SIGNAL")
		)
	)
	(footprint ""
		(layer "F.Cu")
		(at 433.451 -32.893 180)
		(property "Reference" "R24"
			(at 0 0 180)
			(layer "F.SilkS")
			(hide yes)
			(effects
				(font
					(size 1.27 1.27)
				)
			)
		)
		(property "Value" ""
			(at 0 0 180)
			(layer "F.Fab")
			(effects
				(font
					(size 1.27 1.27)
				)
			)
		)
		(duplicate_pad_numbers_are_jumpers no)
		(fp_line
			(start 0.7874 0.4064)
			(end -0.7874 0.4064)
			(stroke
				(width 0.1524)
				(type default)
			)
			(layer "F.SilkS")
		)
		(fp_line
			(start 0.7874 -0.4064)
			(end 0.7874 0.4064)
			(stroke
				(width 0.1524)
				(type default)
			)
			(layer "F.SilkS")
		)
		(fp_line
			(start -0.7874 0.4064)
			(end -0.7874 -0.4064)
			(stroke
				(width 0.1524)
				(type default)
			)
			(layer "F.SilkS")
		)
		(fp_line
			(start -0.7874 -0.4064)
			(end 0.7874 -0.4064)
			(stroke
				(width 0.1524)
				(type default)
			)
			(layer "F.SilkS")
		)
		(fp_line
			(start 0.67945 0.3048)
			(end 0.120396 0.3048)
			(stroke
				(width 0.1)
				(type default)
			)
			(layer "F.Fab")
		)
		(fp_line
			(start 0.67945 -0.3048)
			(end 0.67945 0.3048)
			(stroke
				(width 0.1)
				(type default)
			)
			(layer "F.Fab")
		)
		(fp_line
			(start 0.12065 -0.2794)
			(end 0.12065 -0.3048)
			(stroke
				(width 0.1)
				(type default)
			)
			(layer "F.Fab")
		)
		(fp_line
			(start 0.12065 -0.3048)
			(end 0.67945 -0.3048)
			(stroke
				(width 0.1)
				(type default)
			)
			(layer "F.Fab")
		)
		(fp_line
			(start 0.120396 0.3048)
			(end 0.120396 0.2794)
			(stroke
				(width 0.1)
				(type default)
			)
			(layer "F.Fab")
		)
		(fp_line
			(start 0.120396 0.2794)
			(end -0.12065 0.2794)
			(stroke
				(width 0.1)
				(type default)
			)
			(layer "F.Fab")
		)
		(fp_line
			(start -0.12065 0.3048)
			(end -0.67945 0.3048)
			(stroke
				(width 0.1)
				(type default)
			)
			(layer "F.Fab")
		)
		(fp_line
			(start -0.12065 0.2794)
			(end -0.12065 0.3048)
			(stroke
				(width 0.1)
				(type default)
			)
			(layer "F.Fab")
		)
		(fp_line
			(start -0.12065 -0.2794)
			(end 0.12065 -0.2794)
			(stroke
				(width 0.1)
				(type default)
			)
			(layer "F.Fab")
		)
		(fp_line
			(start -0.12065 -0.305054)
			(end -0.12065 -0.2794)
			(stroke
				(width 0.1)
				(type default)
			)
			(layer "F.Fab")
		)
		(fp_line
			(start -0.67945 0.3048)
			(end -0.67945 -0.305054)
			(stroke
				(width 0.1)
				(type default)
			)
			(layer "F.Fab")
		)
		(fp_line
			(start -0.67945 -0.305054)
			(end -0.12065 -0.305054)
			(stroke
				(width 0.1)
				(type default)
			)
			(layer "F.Fab")
		)
		(pad "1" smd circle
			(at -0.40005 0 180)
			(size 0 0)
			(layers "F.Cu" "F.Mask" "F.Paste")
			(net "PD_9543_FAN_A1")
		)
		(pad "2" smd circle
			(at 0.40005 0 180)
			(size 0 0)
			(layers "F.Cu" "F.Mask" "F.Paste")
			(net "GND")
		)
	)
	(footprint ""
		(layer "F.Cu")
		(at 360.000296 -142.499842 180)
		(property "Reference" "H11"
			(at 0.844296 -6.509512 0)
			(unlocked yes)
			(layer "F.SilkS")
			(effects
				(font
					(size 0.7874 0.5842)
					(thickness 0.1524)
				)
				(justify left)
			)
		)
		(property "Value" ""
			(at 0 0 180)
			(layer "F.Fab")
			(effects
				(font
					(size 1.27 1.27)
				)
			)
		)
		(duplicate_pad_numbers_are_jumpers no)
		(pad "1" thru_hole oval
			(at 0 0 180)
			(size 9.017 14.0208)
			(drill 3.0226
				(offset 0 2.499868)
			)
			(layers "*.Cu" "*.Mask")
			(remove_unused_layers no)
			(net "GND")
			(clearance -1.500378)
			(padstack
				(mode front_inner_back)
				(layer "Inner"
					(shape circle)
					(size 0 0)
					(clearance 0)
				)
				(layer "B.Cu"
					(shape oval)
					(size 9.017 14.0208)
					(offset 0 2.499868)
					(clearance -1.500378)
				)
			)
		)
	)
	(footprint ""
		(layer "F.Cu")
		(at 411.72384 -27.852878 90)
		(property "Reference" "R5921"
			(at 0 0 90)
			(layer "F.SilkS")
			(hide yes)
			(effects
				(font
					(size 1.27 1.27)
				)
			)
		)
		(property "Value" ""
			(at 0 0 90)
			(layer "F.Fab")
			(effects
				(font
					(size 1.27 1.27)
				)
			)
		)
		(duplicate_pad_numbers_are_jumpers no)
		(fp_line
			(start 0.7874 -0.4064)
			(end 0.7874 0.4064)
			(stroke
				(width 0.1524)
				(type default)
			)
			(layer "F.SilkS")
		)
		(fp_line
			(start -0.7874 -0.4064)
			(end 0.7874 -0.4064)
			(stroke
				(width 0.1524)
				(type default)
			)
			(layer "F.SilkS")
		)
		(fp_line
			(start 0.7874 0.4064)
			(end -0.7874 0.4064)
			(stroke
				(width 0.1524)
				(type default)
			)
			(layer "F.SilkS")
		)
		(fp_line
			(start -0.7874 0.4064)
			(end -0.7874 -0.4064)
			(stroke
				(width 0.1524)
				(type default)
			)
			(layer "F.SilkS")
		)
		(fp_line
			(start -0.12065 -0.305054)
			(end -0.12065 -0.2794)
			(stroke
				(width 0.1)
				(type default)
			)
			(layer "F.Fab")
		)
		(fp_line
			(start -0.67945 -0.305054)
			(end -0.12065 -0.305054)
			(stroke
				(width 0.1)
				(type default)
			)
			(layer "F.Fab")
		)
		(fp_line
			(start 0.67945 -0.3048)
			(end 0.67945 0.3048)
			(stroke
				(width 0.1)
				(type default)
			)
			(layer "F.Fab")
		)
		(fp_line
			(start 0.12065 -0.3048)
			(end 0.67945 -0.3048)
			(stroke
				(width 0.1)
				(type default)
			)
			(layer "F.Fab")
		)
		(fp_line
			(start 0.12065 -0.2794)
			(end 0.12065 -0.3048)
			(stroke
				(width 0.1)
				(type default)
			)
			(layer "F.Fab")
		)
		(fp_line
			(start -0.12065 -0.2794)
			(end 0.12065 -0.2794)
			(stroke
				(width 0.1)
				(type default)
			)
			(layer "F.Fab")
		)
		(fp_line
			(start 0.120396 0.2794)
			(end -0.12065 0.2794)
			(stroke
				(width 0.1)
				(type default)
			)
			(layer "F.Fab")
		)
		(fp_line
			(start -0.12065 0.2794)
			(end -0.12065 0.3048)
			(stroke
				(width 0.1)
				(type default)
			)
			(layer "F.Fab")
		)
		(fp_line
			(start 0.67945 0.3048)
			(end 0.120396 0.3048)
			(stroke
				(width 0.1)
				(type default)
			)
			(layer "F.Fab")
		)
		(fp_line
			(start 0.120396 0.3048)
			(end 0.120396 0.2794)
			(stroke
				(width 0.1)
				(type default)
			)
			(layer "F.Fab")
		)
		(fp_line
			(start -0.12065 0.3048)
			(end -0.67945 0.3048)
			(stroke
				(width 0.1)
				(type default)
			)
			(layer "F.Fab")
		)
		(fp_line
			(start -0.67945 0.3048)
			(end -0.67945 -0.305054)
			(stroke
				(width 0.1)
				(type default)
			)
			(layer "F.Fab")
		)
		(pad "1" smd rect
			(at -0.40005 0 270)
			(size 0.4572 0.508)
			(layers "F.Cu" "F.Mask" "F.Paste")
			(net "P12V_FAN_LED")
		)
		(pad "2" smd rect
			(at 0.40005 0 270)
			(size 0.4572 0.508)
			(layers "F.Cu" "F.Mask" "F.Paste")
			(net "P12V_LED_FB")
		)
	)
)
